# S9S_MB_2U (Grand Teton) — schematic netlist excerpt (pin names and nets, part order shuffled) for the footprints in the layout excerpt that follows; sources: Cadence DE-HDL packaged netlist, KiCad conversion of 03242023_DA0F0TMBIJ0_F0T_Motherboard_J_brd_V01_OCP.brd

R1021  Q_RES  0 5% CHIP  pkg 0402LF  page 209 : A = CLK_25M_CK440_CPU0_R_DN ; B = CLK_25M_NSSC_CPU0_DN
D42  SCHOTTKY_12  B0530WS7F IC  pkg SOD323XB  page 115 : A = PWRGD_FAIL_CPU0_AB_R1 ; C = P3V3_AUX

(kicad_pcb
	(version 20260206)
	(generator "pcbnew")
	(generator_version "10.0")
	(general
		(thickness 1.6)
		(legacy_teardrops no)
	)
	(paper "A4")
	(title_block
		(title "03242023_DA0F0TMBIJ0_F0T_Motherboard_J_brd_V01_OCP.brd")
		(comment 1 "Grand Teton / footprints 4472-4473 of 6105")
	)
	(layers
		(0 "F.Cu" signal "TOP")
		(4 "In1.Cu" signal "GND")
		(6 "In2.Cu" signal "IN1")
		(8 "In3.Cu" signal "GND1")
		(10 "In4.Cu" signal "IN2")
		(12 "In5.Cu" signal "GND2")
		(14 "In6.Cu" signal "IN3")
		(16 "In7.Cu" signal "GND3")
		(18 "In8.Cu" signal "VCC")
		(20 "In9.Cu" signal "VCC1")
		(22 "In10.Cu" signal "GND4")
		(24 "In11.Cu" signal "IN4")
		(26 "In12.Cu" signal "GND5")
		(28 "In13.Cu" signal "IN5")
		(30 "In14.Cu" signal "GND6")
		(32 "In15.Cu" signal "IN6")
		(34 "In16.Cu" signal "GND7")
		(2 "B.Cu" signal "BOTTOM")
		(9 "F.Adhes" user "F.Adhesive")
		(11 "B.Adhes" user "B.Adhesive")
		(13 "F.Paste" user "Package Geometry/Pastemask Top")
		(15 "B.Paste" user "Package Geometry/Pastemask Bottom")
		(5 "F.SilkS" user "Ref Des/Silkscreen Top")
		(7 "B.SilkS" user "Ref Des/Silkscreen Bottom")
		(1 "F.Mask" user "Board Geometry/Soldermask Top")
		(3 "B.Mask" user "Board Geometry/Soldermask Bottom")
		(17 "Dwgs.User" user "User.Drawings")
		(19 "Cmts.User" user "User.Comments")
		(21 "Eco1.User" user "User.Eco1")
		(23 "Eco2.User" user "User.Eco2")
		(25 "Edge.Cuts" user "Board Geometry/Outline")
		(27 "Margin" user)
		(31 "F.CrtYd" user "Package Geometry/Place Bound Top")
		(29 "B.CrtYd" user "Package Geometry/Place Bound Bottom")
		(35 "F.Fab" user "Ref Des/Assembly Top")
		(33 "B.Fab" user "Ref Des/Assembly Bottom")
	)
	(footprint ""
		(layer "B.Cu")
		(at 337.622134 -136.479534 180)
		(property "Reference" "R1021"
			(at 0 0 0)
			(layer "B.SilkS")
			(hide yes)
			(effects
				(font
					(size 1.27 1.27)
				)
				(justify mirror)
			)
		)
		(property "Value" ""
			(at 0 0 0)
			(layer "B.Fab")
			(effects
				(font
					(size 1.27 1.27)
				)
				(justify mirror)
			)
		)
		(duplicate_pad_numbers_are_jumpers no)
		(fp_line
			(start 0.7874 -0.083566)
			(end 0.7874 -0.4064)
			(stroke
				(width 0.1524)
				(type default)
			)
			(layer "B.SilkS")
		)
		(fp_line
			(start 0.7874 -0.4064)
			(end -0.7874 -0.4064)
			(stroke
				(width 0.1524)
				(type default)
			)
			(layer "B.SilkS")
		)
		(fp_line
			(start -0.169926 0.4064)
			(end 0.495554 0.4064)
			(stroke
				(width 0.1524)
				(type default)
			)
			(layer "B.SilkS")
		)
		(fp_line
			(start -0.7874 0.4064)
			(end -0.604266 0.4064)
			(stroke
				(width 0.1524)
				(type default)
			)
			(layer "B.SilkS")
		)
		(fp_line
			(start -0.7874 -0.4064)
			(end -0.7874 0.4064)
			(stroke
				(width 0.1524)
				(type default)
			)
			(layer "B.SilkS")
		)
		(fp_line
			(start 0.67945 0.3048)
			(end 0.67945 -0.305054)
			(stroke
				(width 0.1)
				(type default)
			)
			(layer "B.Fab")
		)
		(fp_line
			(start 0.67945 -0.305054)
			(end 0.12065 -0.305054)
			(stroke
				(width 0.1)
				(type default)
			)
			(layer "B.Fab")
		)
		(fp_line
			(start 0.12065 0.3048)
			(end 0.67945 0.3048)
			(stroke
				(width 0.1)
				(type default)
			)
			(layer "B.Fab")
		)
		(fp_line
			(start 0.12065 0.2794)
			(end 0.12065 0.3048)
			(stroke
				(width 0.1)
				(type default)
			)
			(layer "B.Fab")
		)
		(fp_line
			(start 0.12065 -0.2794)
			(end -0.12065 -0.2794)
			(stroke
				(width 0.1)
				(type default)
			)
			(layer "B.Fab")
		)
		(fp_line
			(start 0.12065 -0.305054)
			(end 0.12065 -0.2794)
			(stroke
				(width 0.1)
				(type default)
			)
			(layer "B.Fab")
		)
		(fp_line
			(start -0.120396 0.3048)
			(end -0.120396 0.2794)
			(stroke
				(width 0.1)
				(type default)
			)
			(layer "B.Fab")
		)
		(fp_line
			(start -0.120396 0.2794)
			(end 0.12065 0.2794)
			(stroke
				(width 0.1)
				(type default)
			)
			(layer "B.Fab")
		)
		(fp_line
			(start -0.12065 -0.2794)
			(end -0.12065 -0.3048)
			(stroke
				(width 0.1)
				(type default)
			)
			(layer "B.Fab")
		)
		(fp_line
			(start -0.12065 -0.3048)
			(end -0.67945 -0.3048)
			(stroke
				(width 0.1)
				(type default)
			)
			(layer "B.Fab")
		)
		(fp_line
			(start -0.67945 0.3048)
			(end -0.120396 0.3048)
			(stroke
				(width 0.1)
				(type default)
			)
			(layer "B.Fab")
		)
		(fp_line
			(start -0.67945 -0.3048)
			(end -0.67945 0.3048)
			(stroke
				(width 0.1)
				(type default)
			)
			(layer "B.Fab")
		)
		(pad "1" smd rect
			(at 0.40005 0 180)
			(size 0.4572 0.508)
			(layers "B.Cu" "B.Mask" "B.Paste")
			(net "CLK_25M_CK440_CPU0_R_DN")
		)
		(pad "2" smd rect
			(at -0.40005 0 180)
			(size 0.4572 0.508)
			(layers "B.Cu" "B.Mask" "B.Paste")
			(net "CLK_25M_NSSC_CPU0_DN")
		)
	)
	(footprint ""
		(layer "B.Cu")
		(at 308.901846 -316.14999 -90)
		(property "Reference" "D42"
			(at 1.284732 1.231646 0)
			(unlocked yes)
			(layer "B.SilkS")
			(effects
				(font
					(size 0.7874 0.5842)
					(thickness 0.1524)
				)
				(justify left mirror)
			)
		)
		(property "Value" ""
			(at 0 0 90)
			(layer "B.Fab")
			(effects
				(font
					(size 1.27 1.27)
				)
				(justify mirror)
			)
		)
		(duplicate_pad_numbers_are_jumpers no)
		(fp_line
			(start -2.050796 0.700024)
			(end 2.050796 0.700024)
			(stroke
				(width 0.1524)
				(type default)
			)
			(layer "B.SilkS")
		)
		(fp_line
			(start 2.050796 0.700024)
			(end 2.050796 -0.700024)
			(stroke
				(width 0.1524)
				(type default)
			)
			(layer "B.SilkS")
		)
		(fp_line
			(start -2.343404 0.6985)
			(end -2.216404 0.6985)
			(stroke
				(width 0.1524)
				(type default)
			)
			(layer "B.SilkS")
		)
		(fp_line
			(start -2.229104 0.6985)
			(end -2.051304 0.6985)
			(stroke
				(width 0.1524)
				(type default)
			)
			(layer "B.SilkS")
		)
		(fp_line
			(start -2.051304 0.6985)
			(end -2.051304 0.635)
			(stroke
				(width 0.1524)
				(type default)
			)
			(layer "B.SilkS")
		)
		(fp_line
			(start -2.152904 0.635)
			(end -2.152904 -0.6985)
			(stroke
				(width 0.1524)
				(type default)
			)
			(layer "B.SilkS")
		)
		(fp_line
			(start -2.051304 0.635)
			(end -2.152904 0.635)
			(stroke
				(width 0.1524)
				(type default)
			)
			(layer "B.SilkS")
		)
		(fp_line
			(start 0.30607 0.500126)
			(end -0.193802 0)
			(stroke
				(width 0.1524)
				(type default)
			)
			(layer "B.SilkS")
		)
		(fp_line
			(start -0.193802 0)
			(end 0.30607 -0.500126)
			(stroke
				(width 0.1524)
				(type default)
			)
			(layer "B.SilkS")
		)
		(fp_line
			(start -0.293878 -0.500126)
			(end -0.293878 0.500126)
			(stroke
				(width 0.1524)
				(type default)
			)
			(layer "B.SilkS")
		)
		(fp_line
			(start 0.30607 -0.500126)
			(end 0.30607 0.500126)
			(stroke
				(width 0.1524)
				(type default)
			)
			(layer "B.SilkS")
		)
		(fp_line
			(start -2.064004 -0.6731)
			(end -2.064004 -0.6985)
			(stroke
				(width 0.1524)
				(type default)
			)
			(layer "B.SilkS")
		)
		(fp_line
			(start -2.343404 -0.6985)
			(end -2.343404 0.6985)
			(stroke
				(width 0.1524)
				(type default)
			)
			(layer "B.SilkS")
		)
		(fp_line
			(start -2.229104 -0.6985)
			(end -2.229104 0.6985)
			(stroke
				(width 0.1524)
				(type default)
			)
			(layer "B.SilkS")
		)
		(fp_line
			(start -2.152904 -0.6985)
			(end -2.343404 -0.6985)
			(stroke
				(width 0.1524)
				(type default)
			)
			(layer "B.SilkS")
		)
		(fp_line
			(start -2.064004 -0.6985)
			(end -2.229104 -0.6985)
			(stroke
				(width 0.1524)
				(type default)
			)
			(layer "B.SilkS")
		)
		(fp_line
			(start -2.050796 -0.700024)
			(end -2.050796 0.700024)
			(stroke
				(width 0.1524)
				(type default)
			)
			(layer "B.SilkS")
		)
		(fp_line
			(start 2.050796 -0.700024)
			(end -2.050796 -0.700024)
			(stroke
				(width 0.1524)
				(type default)
			)
			(layer "B.SilkS")
		)
		(fp_line
			(start -0.899922 0.700024)
			(end 0.899922 0.700024)
			(stroke
				(width 0.1)
				(type default)
			)
			(layer "B.Fab")
		)
		(fp_line
			(start 0.899922 0.700024)
			(end 0.899922 -0.700024)
			(stroke
				(width 0.1)
				(type default)
			)
			(layer "B.Fab")
		)
		(fp_line
			(start -0.899922 -0.700024)
			(end -0.899922 0.700024)
			(stroke
				(width 0.1)
				(type default)
			)
			(layer "B.Fab")
		)
		(fp_line
			(start 0.899922 -0.700024)
			(end -0.899922 -0.700024)
			(stroke
				(width 0.1)
				(type default)
			)
			(layer "B.Fab")
		)
		(fp_text user "-"
			(at -3.65633 0.895096 90)
			(unlocked yes)
			(layer "B.SilkS")
			(effects
				(font
					(size 1.905 1.4224)
					(thickness 0.1524)
				)
				(justify left mirror)
			)
		)
		(fp_text user "+"
			(at 3.123946 0.762 180)
			(unlocked yes)
			(layer "B.SilkS")
			(effects
				(font
					(size 1.905 1.4224)
					(thickness 0.1524)
				)
				(justify left mirror)
			)
		)
		(fp_text user "+"
			(at 3.123946 0.762 180)
			(unlocked yes)
			(layer "B.Fab")
			(effects
				(font
					(size 1.905 1.4224)
					(thickness 0.1524)
				)
				(justify left mirror)
			)
		)
		(fp_text user "-"
			(at -3.880104 0.23495 90)
			(unlocked yes)
			(layer "B.Fab")
			(effects
				(font
					(size 1.905 1.4224)
					(thickness 0.1524)
				)
				(justify left mirror)
			)
		)
		(pad "1" smd rect
			(at 1.199896 0 180)
			(size 0.6604 1.3716)
			(layers "B.Cu" "B.Mask" "B.Paste")
			(net "PWRGD_FAIL_CPU0_AB_R1")
		)
		(pad "2" smd rect
			(at -1.199896 0)
			(size 0.6604 1.3716)
			(layers "B.Cu" "B.Mask" "B.Paste")
			(net "P3V3_AUX")
		)
	)
)
